# T6G (Grand Teton) — schematic netlist excerpt (pin names and nets, part order shuffled) for the footprints in the layout excerpt that follows; sources: Cadence DE-HDL packaged netlist, KiCad conversion of 04192023_DAF0TMB3IC0_F0TG_MB_C_brd_V02_OCP.brd

R4079  Q_RES  10K 1% CHIP  pkg 0402LF  page 233 : A = FG_SS_EN ; B = GND
R87  Q_RES  1K 1% CHIP  pkg 0402LF  page 132 : A = RMII_BMC_OCP_RX_ER ; B = GND
C1549  Q_CAP_DIFFBUS  DIFF BUS_0.22UF 6.3V 20% X6S  pkg C0201  page 65 : \1\ = P5E_CPU0_G3_TX_C_DP<15> ; \2\ = P5E_CPU0_G3_TX_DP<15>

(kicad_pcb
	(version 20260206)
	(generator "pcbnew")
	(generator_version "10.0")
	(general
		(thickness 1.6)
		(legacy_teardrops no)
	)
	(paper "A4")
	(title_block
		(title "04192023_DAF0TMB3IC0_F0TG_MB_C_brd_V02_OCP.brd")
		(comment 1 "Grand Teton / footprints 2145-2147 of 8354")
	)
	(layers
		(0 "F.Cu" signal "TOP")
		(4 "In1.Cu" signal "GND")
		(6 "In2.Cu" signal "IN1")
		(8 "In3.Cu" signal "GND1")
		(10 "In4.Cu" signal "IN2")
		(12 "In5.Cu" signal "GND2")
		(14 "In6.Cu" signal "IN3")
		(16 "In7.Cu" signal "GND3")
		(18 "In8.Cu" signal "VCC")
		(20 "In9.Cu" signal "VCC1")
		(22 "In10.Cu" signal "GND4")
		(24 "In11.Cu" signal "IN4")
		(26 "In12.Cu" signal "GND5")
		(28 "In13.Cu" signal "IN5")
		(30 "In14.Cu" signal "GND6")
		(32 "In15.Cu" signal "IN6")
		(34 "In16.Cu" signal "GND7")
		(2 "B.Cu" signal "BOTTOM")
		(9 "F.Adhes" user "F.Adhesive")
		(11 "B.Adhes" user "B.Adhesive")
		(13 "F.Paste" user "Package Geometry/Pastemask Top")
		(15 "B.Paste" user "Package Geometry/Pastemask Bottom")
		(5 "F.SilkS" user "Ref Des/Silkscreen Top")
		(7 "B.SilkS" user "Ref Des/Silkscreen Bottom")
		(1 "F.Mask" user "Board Geometry/Soldermask Top")
		(3 "B.Mask" user "Board Geometry/Soldermask Bottom")
		(17 "Dwgs.User" user "User.Drawings")
		(19 "Cmts.User" user "User.Comments")
		(21 "Eco1.User" user "User.Eco1")
		(23 "Eco2.User" user "User.Eco2")
		(25 "Edge.Cuts" user "Board Geometry/Outline")
		(27 "Margin" user)
		(31 "F.CrtYd" user "Package Geometry/Place Bound Top")
		(29 "B.CrtYd" user "Package Geometry/Place Bound Bottom")
		(35 "F.Fab" user "Ref Des/Assembly Top")
		(33 "B.Fab" user "Ref Des/Assembly Bottom")
	)
	(footprint ""
		(layer "F.Cu")
		(at 12.351004 -139.25804 90)
		(property "Reference" "R4079"
			(at 0 0 90)
			(layer "F.SilkS")
			(hide yes)
			(effects
				(font
					(size 1.27 1.27)
				)
			)
		)
		(property "Value" ""
			(at 0 0 90)
			(layer "F.Fab")
			(effects
				(font
					(size 1.27 1.27)
				)
			)
		)
		(duplicate_pad_numbers_are_jumpers no)
		(fp_line
			(start 0.7874 -0.4064)
			(end 0.7874 0.4064)
			(stroke
				(width 0.1524)
				(type default)
			)
			(layer "F.SilkS")
		)
		(fp_line
			(start -0.7874 -0.4064)
			(end 0.7874 -0.4064)
			(stroke
				(width 0.1524)
				(type default)
			)
			(layer "F.SilkS")
		)
		(fp_line
			(start 0.7874 0.4064)
			(end -0.7874 0.4064)
			(stroke
				(width 0.1524)
				(type default)
			)
			(layer "F.SilkS")
		)
		(fp_line
			(start -0.7874 0.4064)
			(end -0.7874 -0.4064)
			(stroke
				(width 0.1524)
				(type default)
			)
			(layer "F.SilkS")
		)
		(fp_line
			(start -0.12065 -0.305054)
			(end -0.12065 -0.2794)
			(stroke
				(width 0.1)
				(type default)
			)
			(layer "F.Fab")
		)
		(fp_line
			(start -0.67945 -0.305054)
			(end -0.12065 -0.305054)
			(stroke
				(width 0.1)
				(type default)
			)
			(layer "F.Fab")
		)
		(fp_line
			(start 0.67945 -0.3048)
			(end 0.67945 0.3048)
			(stroke
				(width 0.1)
				(type default)
			)
			(layer "F.Fab")
		)
		(fp_line
			(start 0.12065 -0.3048)
			(end 0.67945 -0.3048)
			(stroke
				(width 0.1)
				(type default)
			)
			(layer "F.Fab")
		)
		(fp_line
			(start 0.12065 -0.2794)
			(end 0.12065 -0.3048)
			(stroke
				(width 0.1)
				(type default)
			)
			(layer "F.Fab")
		)
		(fp_line
			(start -0.12065 -0.2794)
			(end 0.12065 -0.2794)
			(stroke
				(width 0.1)
				(type default)
			)
			(layer "F.Fab")
		)
		(fp_line
			(start 0.120396 0.2794)
			(end -0.12065 0.2794)
			(stroke
				(width 0.1)
				(type default)
			)
			(layer "F.Fab")
		)
		(fp_line
			(start -0.12065 0.2794)
			(end -0.12065 0.3048)
			(stroke
				(width 0.1)
				(type default)
			)
			(layer "F.Fab")
		)
		(fp_line
			(start 0.67945 0.3048)
			(end 0.120396 0.3048)
			(stroke
				(width 0.1)
				(type default)
			)
			(layer "F.Fab")
		)
		(fp_line
			(start 0.120396 0.3048)
			(end 0.120396 0.2794)
			(stroke
				(width 0.1)
				(type default)
			)
			(layer "F.Fab")
		)
		(fp_line
			(start -0.12065 0.3048)
			(end -0.67945 0.3048)
			(stroke
				(width 0.1)
				(type default)
			)
			(layer "F.Fab")
		)
		(fp_line
			(start -0.67945 0.3048)
			(end -0.67945 -0.305054)
			(stroke
				(width 0.1)
				(type default)
			)
			(layer "F.Fab")
		)
		(pad "1" smd circle
			(at -0.40005 0 90)
			(size 0 0)
			(layers "F.Cu" "F.Mask" "F.Paste")
			(net "FG_SS_EN")
		)
		(pad "2" smd circle
			(at 0.40005 0 90)
			(size 0 0)
			(layers "F.Cu" "F.Mask" "F.Paste")
			(net "GND")
		)
	)
	(footprint ""
		(layer "F.Cu")
		(at 166.070534 -21.783548 90)
		(property "Reference" "R87"
			(at 0 0 90)
			(layer "F.SilkS")
			(hide yes)
			(effects
				(font
					(size 1.27 1.27)
				)
			)
		)
		(property "Value" ""
			(at 0 0 90)
			(layer "F.Fab")
			(effects
				(font
					(size 1.27 1.27)
				)
			)
		)
		(duplicate_pad_numbers_are_jumpers no)
		(fp_line
			(start 0.7874 -0.4064)
			(end 0.7874 0.4064)
			(stroke
				(width 0.1524)
				(type default)
			)
			(layer "F.SilkS")
		)
		(fp_line
			(start -0.7874 -0.4064)
			(end 0.7874 -0.4064)
			(stroke
				(width 0.1524)
				(type default)
			)
			(layer "F.SilkS")
		)
		(fp_line
			(start 0.7874 0.4064)
			(end -0.7874 0.4064)
			(stroke
				(width 0.1524)
				(type default)
			)
			(layer "F.SilkS")
		)
		(fp_line
			(start -0.7874 0.4064)
			(end -0.7874 -0.4064)
			(stroke
				(width 0.1524)
				(type default)
			)
			(layer "F.SilkS")
		)
		(fp_line
			(start -0.12065 -0.305054)
			(end -0.12065 -0.2794)
			(stroke
				(width 0.1)
				(type default)
			)
			(layer "F.Fab")
		)
		(fp_line
			(start -0.67945 -0.305054)
			(end -0.12065 -0.305054)
			(stroke
				(width 0.1)
				(type default)
			)
			(layer "F.Fab")
		)
		(fp_line
			(start 0.67945 -0.3048)
			(end 0.67945 0.3048)
			(stroke
				(width 0.1)
				(type default)
			)
			(layer "F.Fab")
		)
		(fp_line
			(start 0.12065 -0.3048)
			(end 0.67945 -0.3048)
			(stroke
				(width 0.1)
				(type default)
			)
			(layer "F.Fab")
		)
		(fp_line
			(start 0.12065 -0.2794)
			(end 0.12065 -0.3048)
			(stroke
				(width 0.1)
				(type default)
			)
			(layer "F.Fab")
		)
		(fp_line
			(start -0.12065 -0.2794)
			(end 0.12065 -0.2794)
			(stroke
				(width 0.1)
				(type default)
			)
			(layer "F.Fab")
		)
		(fp_line
			(start 0.120396 0.2794)
			(end -0.12065 0.2794)
			(stroke
				(width 0.1)
				(type default)
			)
			(layer "F.Fab")
		)
		(fp_line
			(start -0.12065 0.2794)
			(end -0.12065 0.3048)
			(stroke
				(width 0.1)
				(type default)
			)
			(layer "F.Fab")
		)
		(fp_line
			(start 0.67945 0.3048)
			(end 0.120396 0.3048)
			(stroke
				(width 0.1)
				(type default)
			)
			(layer "F.Fab")
		)
		(fp_line
			(start 0.120396 0.3048)
			(end 0.120396 0.2794)
			(stroke
				(width 0.1)
				(type default)
			)
			(layer "F.Fab")
		)
		(fp_line
			(start -0.12065 0.3048)
			(end -0.67945 0.3048)
			(stroke
				(width 0.1)
				(type default)
			)
			(layer "F.Fab")
		)
		(fp_line
			(start -0.67945 0.3048)
			(end -0.67945 -0.305054)
			(stroke
				(width 0.1)
				(type default)
			)
			(layer "F.Fab")
		)
		(pad "1" smd circle
			(at -0.40005 0 90)
			(size 0 0)
			(layers "F.Cu" "F.Mask" "F.Paste")
			(net "RMII_BMC_OCP_RX_ER")
		)
		(pad "2" smd circle
			(at 0.40005 0 90)
			(size 0 0)
			(layers "F.Cu" "F.Mask" "F.Paste")
			(net "GND")
		)
	)
	(footprint ""
		(layer "F.Cu")
		(at 390.921748 -16.100298 90)
		(property "Reference" "C1549"
			(at 0 0 90)
			(layer "F.SilkS")
			(hide yes)
			(effects
				(font
					(size 1.27 1.27)
				)
			)
		)
		(property "Value" ""
			(at 0 0 90)
			(layer "F.Fab")
			(effects
				(font
					(size 1.27 1.27)
				)
			)
		)
		(duplicate_pad_numbers_are_jumpers no)
		(fp_line
			(start 0.299974 -0.150114)
			(end 0.299974 0.150114)
			(stroke
				(width 0.1)
				(type default)
			)
			(layer "F.Fab")
		)
		(fp_line
			(start -0.299974 -0.150114)
			(end 0.299974 -0.150114)
			(stroke
				(width 0.1)
				(type default)
			)
			(layer "F.Fab")
		)
		(fp_line
			(start 0.299974 0.150114)
			(end -0.299974 0.150114)
			(stroke
				(width 0.1)
				(type default)
			)
			(layer "F.Fab")
		)
		(fp_line
			(start -0.299974 0.150114)
			(end -0.299974 -0.150114)
			(stroke
				(width 0.1)
				(type default)
			)
			(layer "F.Fab")
		)
		(pad "1" smd rect
			(at -0.2667 0 90)
			(size 0.3048 0.381)
			(layers "F.Cu" "F.Mask" "F.Paste")
			(net "P5E_CPU0_G3_TX_C_DP<15>")
		)
		(pad "2" smd rect
			(at 0.2667 0 90)
			(size 0.3048 0.381)
			(layers "F.Cu" "F.Mask" "F.Paste")
			(net "P5E_CPU0_G3_TX_DP<15>")
		)
	)
)
